(kicad_pcb
	(version 20241229)
	(generator "pcbnew")
	(generator_version "9.0")
	(general
		(thickness 1.552)
		(legacy_teardrops no)
	)
	(paper "A4")
	(title_block
		(date "2023-07-25")
		(rev "1.1.4")
		(comment 9 "footprints 1-6 of 379")
	)
	(layers
		(0 "F.Cu" signal)
		(4 "In1.Cu" signal)
		(6 "In2.Cu" signal)
		(8 "In3.Cu" signal)
		(10 "In4.Cu" signal)
		(12 "In5.Cu" signal)
		(14 "In6.Cu" signal)
		(2 "B.Cu" signal)
		(9 "F.Adhes" user "F.Adhesive")
		(11 "B.Adhes" user "B.Adhesive")
		(13 "F.Paste" user)
		(15 "B.Paste" user)
		(5 "F.SilkS" user "F.Silkscreen")
		(7 "B.SilkS" user "B.Silkscreen")
		(1 "F.Mask" user)
		(3 "B.Mask" user)
		(17 "Dwgs.User" user "User.Drawings")
		(19 "Cmts.User" user "User.Comments")
		(21 "Eco1.User" user "User.Eco1")
		(23 "Eco2.User" user "User.Eco2")
		(25 "Edge.Cuts" user)
		(27 "Margin" user)
		(31 "F.CrtYd" user "F.Courtyard")
		(29 "B.CrtYd" user "B.Courtyard")
		(35 "F.Fab" user)
		(33 "B.Fab" user)
	)
	(footprint "antmicro-footprints:SOT-23-5"
		(layer "F.Cu")
		(at 141.69 106.9 180)
		(property "Reference" "U8"
			(at -2.34 1.96 0)
			(layer "F.SilkS")
			(effects
				(font
					(size 0.65 0.65)
					(thickness 0.15)
				)
				(justify right bottom)
			)
		)
		(property "Value" "AP7330-W5-7"
			(at 0.002 2.799 0)
			(layer "F.Fab")
			(hide yes)
			(effects
				(font
					(size 0.7 0.7)
					(thickness 0.15)
				)
				(justify right bottom)
			)
		)
		(property "Datasheet" "https://www.diodes.com/assets/Datasheets/AP7330.pdf"
			(at 0 0 180)
			(layer "F.Fab")
			(hide yes)
			(effects
				(font
					(size 1.27 1.27)
					(thickness 0.15)
				)
			)
		)
		(property "Description" "Voltage regulator"
			(at 0 0 180)
			(layer "F.Fab")
			(hide yes)
			(effects
				(font
					(size 1.27 1.27)
					(thickness 0.15)
				)
			)
		)
		(property "Author" "Antmicro"
			(at 283.38 213.8 0)
			(layer "F.Fab")
			(hide yes)
			(effects
				(font
					(size 1 1)
					(thickness 0.15)
				)
			)
		)
		(property "License" "Apache-2.0"
			(at 283.38 213.8 0)
			(layer "F.Fab")
			(hide yes)
			(effects
				(font
					(size 1 1)
					(thickness 0.15)
				)
			)
		)
		(property "MPN" "AP7330-W5-7"
			(at 283.38 213.8 0)
			(layer "F.Fab")
			(hide yes)
			(effects
				(font
					(size 1 1)
					(thickness 0.15)
				)
			)
		)
		(property "Manufacturer" "Diodes Incorporated"
			(at 283.38 213.8 0)
			(layer "F.Fab")
			(hide yes)
			(effects
				(font
					(size 1 1)
					(thickness 0.15)
				)
			)
		)
		(sheetname "/Power Supply/")
		(sheetfile "supply.kicad_sch")
		(attr smd)
		(fp_line
			(start 0.8 1.599)
			(end 0.549 1.599)
			(stroke
				(width 0.15)
				(type solid)
			)
			(layer "F.SilkS")
		)
		(fp_line
			(start 0.8 1.3)
			(end 0.8 1.599)
			(stroke
				(width 0.15)
				(type solid)
			)
			(layer "F.SilkS")
		)
		(fp_line
			(start 0.8 0.55)
			(end 0.8 -0.55)
			(stroke
				(width 0.15)
				(type solid)
			)
			(layer "F.SilkS")
		)
		(fp_line
			(start 0.8 -1.3)
			(end 0.8 -1.6)
			(stroke
				(width 0.15)
				(type solid)
			)
			(layer "F.SilkS")
		)
		(fp_line
			(start 0.8 -1.6)
			(end 0.5 -1.6)
			(stroke
				(width 0.15)
				(type solid)
			)
			(layer "F.SilkS")
		)
		(fp_line
			(start -0.55 1.6)
			(end -0.85 1.6)
			(stroke
				(width 0.15)
				(type solid)
			)
			(layer "F.SilkS")
		)
		(fp_line
			(start -0.8 -1.6)
			(end -0.5 -1.6)
			(stroke
				(width 0.15)
				(type solid)
			)
			(layer "F.SilkS")
		)
		(fp_line
			(start -0.8 -1.6)
			(end -0.8 -1.3)
			(stroke
				(width 0.15)
				(type solid)
			)
			(layer "F.SilkS")
		)
		(fp_line
			(start -0.85 1.6)
			(end -0.85 1.301)
			(stroke
				(width 0.15)
				(type solid)
			)
			(layer "F.SilkS")
		)
		(fp_circle
			(center -1.25 -1.5)
			(end -1.2 -1.5)
			(stroke
				(width 0.15)
				(type solid)
			)
			(fill yes)
			(layer "F.SilkS")
		)
		(fp_rect
			(start 1.9 -1.76)
			(end -1.9 1.75)
			(stroke
				(width 0.05)
				(type solid)
			)
			(fill no)
			(layer "F.CrtYd")
		)
		(fp_line
			(start -0.398 -1.526)
			(end -0.874 -1.05)
			(stroke
				(width 0.15)
				(type solid)
			)
			(layer "F.Fab")
		)
		(fp_rect
			(start 0.874 1.523)
			(end -0.873 -1.525)
			(stroke
				(width 0.15)
				(type solid)
			)
			(fill no)
			(layer "F.Fab")
		)
		(pad "1" smd rect
			(at -1.351 -0.951 90)
			(size 0.55 1)
			(layers "F.Cu" "F.Mask" "F.Paste")
			(net 264 "Net-(U8-V_{IN})")
			(pinfunction "V_{IN}")
			(pintype "power_in")
		)
		(pad "2" smd rect
			(at -1.351 0 90)
			(size 0.55 1)
			(layers "F.Cu" "F.Mask" "F.Paste")
			(net 1 "GND")
			(pinfunction "GND")
			(pintype "power_in")
		)
		(pad "3" smd rect
			(at -1.351 0.949 90)
			(size 0.55 1)
			(layers "F.Cu" "F.Mask" "F.Paste")
			(net 268 "Net-(U8-EN)")
			(pinfunction "EN")
			(pintype "input")
		)
		(pad "4" smd rect
			(at 1.35 0.949 90)
			(size 0.55 1)
			(layers "F.Cu" "F.Mask" "F.Paste")
			(net 280 "Net-(U8-ADJ)")
			(pinfunction "ADJ")
			(pintype "passive")
		)
		(pad "5" smd rect
			(at 1.35 -0.951 90)
			(size 0.55 1)
			(layers "F.Cu" "F.Mask" "F.Paste")
			(net 272 "Net-(U8-V_{OUT})")
			(pinfunction "V_{OUT}")
			(pintype "power_out")
		)
	)
	(footprint "antmicro-footprints:C_0402_1005Metric"
		(layer "F.Cu")
		(at 84.2 108.15 180)
		(descr "Capacitor SMD 0402")
		(tags "capacitor SMD 0402")
		(property "Reference" "C77"
			(at -4.33 7.81 0)
			(layer "F.SilkS")
			(effects
				(font
					(size 0.65 0.65)
					(thickness 0.15)
				)
				(justify right bottom)
			)
		)
		(property "Value" "C_4u7_0402"
			(at 0 1.4 0)
			(layer "F.Fab")
			(hide yes)
			(effects
				(font
					(size 0.7 0.7)
					(thickness 0.15)
				)
				(justify right bottom)
			)
		)
		(property "Datasheet" "https://www.murata.com/products/productdetail?partno=GRM155R61A475MEAA%23"
			(at 0 0 180)
			(layer "F.Fab")
			(hide yes)
			(effects
				(font
					(size 1.27 1.27)
					(thickness 0.15)
				)
			)
		)
		(property "Description" "SMD Multilayer Ceramic Capacitor, 4.7 µF, 10 V, 0402 [1005 Metric], ± 20%, X5R, GRM Series"
			(at 0 0 180)
			(layer "F.Fab")
			(hide yes)
			(effects
				(font
					(size 1.27 1.27)
					(thickness 0.15)
				)
			)
		)
		(property "Author" "Antmicro"
			(at 168.4 216.3 0)
			(layer "F.Fab")
			(hide yes)
			(effects
				(font
					(size 1 1)
					(thickness 0.15)
				)
			)
		)
		(property "Dielectric" ""
			(at 168.4 216.3 0)
			(layer "F.Fab")
			(hide yes)
			(effects
				(font
					(size 1 1)
					(thickness 0.15)
				)
			)
		)
		(property "License" "Apache-2.0"
			(at 168.4 216.3 0)
			(layer "F.Fab")
			(hide yes)
			(effects
				(font
					(size 1 1)
					(thickness 0.15)
				)
			)
		)
		(property "MPN" "GRM155R61A475MEAAD"
			(at 168.4 216.3 0)
			(layer "F.Fab")
			(hide yes)
			(effects
				(font
					(size 1 1)
					(thickness 0.15)
				)
			)
		)
		(property "Manufacturer" "Murata"
			(at 168.4 216.3 0)
			(layer "F.Fab")
			(hide yes)
			(effects
				(font
					(size 1 1)
					(thickness 0.15)
				)
			)
		)
		(property "Val" "4u7"
			(at 168.4 216.3 0)
			(layer "F.Fab")
			(hide yes)
			(effects
				(font
					(size 1 1)
					(thickness 0.15)
				)
			)
		)
		(property "Voltage" ""
			(at 168.4 216.3 0)
			(layer "F.Fab")
			(hide yes)
			(effects
				(font
					(size 1 1)
					(thickness 0.15)
				)
			)
		)
		(sheetname "/SDI/")
		(sheetfile "sdi.kicad_sch")
		(attr smd)
		(fp_rect
			(start -0.925 -0.47)
			(end 0.925 0.47)
			(stroke
				(width 0.05)
				(type default)
			)
			(fill no)
			(layer "F.CrtYd")
		)
		(fp_line
			(start 0.504 0.248)
			(end -0.494 0.248)
			(stroke
				(width 0.15)
				(type solid)
			)
			(layer "F.Fab")
		)
		(fp_line
			(start 0.504 -0.25)
			(end 0.504 0.248)
			(stroke
				(width 0.15)
				(type solid)
			)
			(layer "F.Fab")
		)
		(fp_line
			(start -0.494 0.248)
			(end -0.494 -0.25)
			(stroke
				(width 0.15)
				(type solid)
			)
			(layer "F.Fab")
		)
		(fp_line
			(start -0.494 -0.25)
			(end 0.504 -0.25)
			(stroke
				(width 0.15)
				(type solid)
			)
			(layer "F.Fab")
		)
		(fp_text user "${REFERENCE}"
			(at -0.939 4.599 180)
			(layer "F.Fab")
			(effects
				(font
					(size 0.7 0.7)
					(thickness 0.15)
				)
				(justify left bottom)
			)
		)
		(fp_text user "License: Apache-2.0"
			(at -0.939 5.799 180)
			(layer "F.Fab")
			(effects
				(font
					(size 0.7 0.7)
					(thickness 0.15)
				)
				(justify left bottom)
			)
		)
		(fp_text user "Author: Antmicro"
			(at -0.939 3.399 180)
			(layer "F.Fab")
			(effects
				(font
					(size 0.7 0.7)
					(thickness 0.15)
				)
				(justify left bottom)
			)
		)
		(pad "1" smd roundrect
			(at -0.48 0 180)
			(size 0.59 0.64)
			(layers "F.Cu" "F.Mask" "F.Paste")
			(roundrect_rratio 0.25)
			(net 249 "/SDI/SDI_OUT_P")
			(pintype "passive")
		)
		(pad "2" smd roundrect
			(at 0.48 0 180)
			(size 0.59 0.64)
			(layers "F.Cu" "F.Mask" "F.Paste")
			(roundrect_rratio 0.25)
			(net 250 "Net-(C77-Pad2)")
			(pintype "passive")
		)
	)
	(footprint "antmicro-footprints:L_0402_1005Metric"
		(layer "F.Cu")
		(at 86.6 76.4 180)
		(descr "Inductor SMD 0402")
		(tags "Inductor SMD 0402")
		(property "Reference" "L4"
			(at 2.77 6.26 180)
			(layer "F.SilkS")
			(effects
				(font
					(size 0.65 0.65)
					(thickness 0.15)
				)
				(justify left bottom)
			)
		)
		(property "Value" "L_6n2_0.7A_0402"
			(at 0 1.4 180)
			(layer "F.Fab")
			(hide yes)
			(effects
				(font
					(size 0.7 0.7)
					(thickness 0.15)
				)
				(justify left bottom)
			)
		)
		(property "Datasheet" "https://www.mouser.com/datasheet/2/281/1/JELF243A_0050-1380872.pdf"
			(at 0 0 180)
			(layer "F.Fab")
			(hide yes)
			(effects
				(font
					(size 1.27 1.27)
					(thickness 0.15)
				)
			)
		)
		(property "Description" "Wirewound Inductor, 6.2 nH, 0.09 ohm, 8 GHz, 700 mA, 0402 [1005 Metric], LQW"
			(at 0 0 180)
			(layer "F.Fab")
			(hide yes)
			(effects
				(font
					(size 1.27 1.27)
					(thickness 0.15)
				)
			)
		)
		(property "Author" "Antmicro"
			(at 173.2 152.8 0)
			(layer "F.Fab")
			(hide yes)
			(effects
				(font
					(size 1 1)
					(thickness 0.15)
				)
			)
		)
		(property "IMax" "0.7 A"
			(at 173.2 152.8 0)
			(layer "F.Fab")
			(hide yes)
			(effects
				(font
					(size 1 1)
					(thickness 0.15)
				)
			)
		)
		(property "ISat" ""
			(at 173.2 152.8 0)
			(layer "F.Fab")
			(hide yes)
			(effects
				(font
					(size 1 1)
					(thickness 0.15)
				)
			)
		)
		(property "License" "Apache-2.0"
			(at 173.2 152.8 0)
			(layer "F.Fab")
			(hide yes)
			(effects
				(font
					(size 1 1)
					(thickness 0.15)
				)
			)
		)
		(property "MPN" "LQW15AN6N2C00D"
			(at 173.2 152.8 0)
			(layer "F.Fab")
			(hide yes)
			(effects
				(font
					(size 1 1)
					(thickness 0.15)
				)
			)
		)
		(property "Manufacturer" "Murata"
			(at 173.2 152.8 0)
			(layer "F.Fab")
			(hide yes)
			(effects
				(font
					(size 1 1)
					(thickness 0.15)
				)
			)
		)
		(property "Size" "1.0x0.5"
			(at 173.2 152.8 0)
			(layer "F.Fab")
			(hide yes)
			(effects
				(font
					(size 1 1)
					(thickness 0.15)
				)
			)
		)
		(property "Val" "6n2/0.7A"
			(at 173.2 152.8 0)
			(layer "F.Fab")
			(hide yes)
			(effects
				(font
					(size 1 1)
					(thickness 0.15)
				)
			)
		)
		(sheetname "/SDI/")
		(sheetfile "sdi.kicad_sch")
		(attr smd)
		(fp_rect
			(start -0.925 -0.47)
			(end 0.925 0.47)
			(stroke
				(width 0.05)
				(type default)
			)
			(fill no)
			(layer "F.CrtYd")
		)
		(fp_rect
			(start -0.499 -0.249)
			(end 0.499 0.249)
			(stroke
				(width 0.15)
				(type solid)
			)
			(fill no)
			(layer "F.Fab")
		)
		(fp_text user "Author: Antmicro"
			(at -0.932 4.17 180)
			(layer "F.Fab")
			(effects
				(font
					(size 0.7 0.7)
					(thickness 0.15)
				)
				(justify left bottom)
			)
		)
		(fp_text user "License: Apache-2.0"
			(at -0.932 5.17 180)
			(layer "F.Fab")
			(effects
				(font
					(size 0.7 0.7)
					(thickness 0.15)
				)
				(justify left bottom)
			)
		)
		(fp_text user "${REFERENCE}"
			(at -0.932 3.168 180)
			(layer "F.Fab")
			(effects
				(font
					(size 0.7 0.7)
					(thickness 0.15)
				)
				(justify left bottom)
			)
		)
		(pad "1" smd roundrect
			(at -0.48 0 180)
			(size 0.59 0.64)
			(layers "F.Cu" "F.Mask" "F.Paste")
			(roundrect_rratio 0.25)
			(net 243 "/SDI/SDI_IN_F")
			(pintype "passive")
		)
		(pad "2" smd roundrect
			(at 0.48 0 180)
			(size 0.59 0.64)
			(layers "F.Cu" "F.Mask" "F.Paste")
			(roundrect_rratio 0.25)
			(net 253 "/SDI/SDI_IN")
			(pintype "passive")
		)
	)
	(footprint "antmicro-footprints:TP_SMD_0.75mm"
		(layer "F.Cu")
		(at 104.9492 90.4 -90)
		(property "Reference" "TP17"
			(at -2.93 0.2792 90)
			(layer "F.SilkS")
			(effects
				(font
					(size 0.65 0.65)
					(thickness 0.15)
				)
				(justify right top)
			)
		)
		(property "Value" "TP_0.75mm_SMD"
			(at 0 1.2 90)
			(layer "F.Fab")
			(hide yes)
			(effects
				(font
					(size 0.7 0.7)
					(thickness 0.15)
				)
				(justify right bottom)
			)
		)
		(property "Description" "SMT test point"
			(at 0 0 90)
			(layer "F.Fab")
			(hide yes)
			(effects
				(font
					(size 1.27 1.27)
					(thickness 0.15)
				)
			)
		)
		(property "Author" "Antmicro"
			(at 14.5492 195.3492 0)
			(layer "F.Fab")
			(hide yes)
			(effects
				(font
					(size 1 1)
					(thickness 0.15)
				)
			)
		)
		(property "License" "Apache-2.0"
			(at 14.5492 195.3492 0)
			(layer "F.Fab")
			(hide yes)
			(effects
				(font
					(size 1 1)
					(thickness 0.15)
				)
			)
		)
		(property "MPN" ""
			(at 14.5492 195.3492 0)
			(layer "F.Fab")
			(hide yes)
			(effects
				(font
					(size 1 1)
					(thickness 0.15)
				)
			)
		)
		(property "Manufacturer" ""
			(at 14.5492 195.3492 0)
			(layer "F.Fab")
			(hide yes)
			(effects
				(font
					(size 1 1)
					(thickness 0.15)
				)
			)
		)
		(sheetname "/FPGA/")
		(sheetfile "fpga.kicad_sch")
		(attr exclude_from_pos_files)
		(fp_circle
			(center 0 0)
			(end 0.475 0)
			(stroke
				(width 0.05)
				(type default)
			)
			(fill no)
			(layer "F.CrtYd")
		)
		(fp_text user "${REFERENCE}"
			(at -0.4 2.7 90)
			(layer "F.Fab")
			(effects
				(font
					(size 0.7 0.7)
					(thickness 0.15)
				)
				(justify right top)
			)
		)
		(fp_text user "Author: Antmicro"
			(at -0.4 3.901 90)
			(layer "F.Fab")
			(effects
				(font
					(size 0.7 0.7)
					(thickness 0.15)
				)
				(justify right top)
			)
		)
		(fp_text user "License: Apache-2.0"
			(at -0.4 5.101 90)
			(layer "F.Fab")
			(effects
				(font
					(size 0.7 0.7)
					(thickness 0.15)
				)
				(justify right top)
			)
		)
		(pad "1" smd circle
			(at 0 0 270)
			(size 0.75 0.75)
			(layers "F.Cu" "F.Mask")
			(net 28 "/FPGA/SPI_DQ2")
			(pinfunction "1")
			(pintype "passive")
		)
	)
	(footprint "antmicro-footprints:TP_SMD_0.75mm"
		(layer "F.Cu")
		(at 102.69 97.1 -90)
		(property "Reference" "TP15"
			(at -0.33 3.06 0)
			(layer "F.SilkS")
			(effects
				(font
					(size 0.65 0.65)
					(thickness 0.15)
				)
				(justify left top)
			)
		)
		(property "Value" "TP_0.75mm_SMD"
			(at 0 1.2 90)
			(layer "F.Fab")
			(hide yes)
			(effects
				(font
					(size 0.7 0.7)
					(thickness 0.15)
				)
				(justify right bottom)
			)
		)
		(property "Description" "SMT test point"
			(at 0 0 90)
			(layer "F.Fab")
			(hide yes)
			(effects
				(font
					(size 1.27 1.27)
					(thickness 0.15)
				)
			)
		)
		(property "Author" "Antmicro"
			(at 5.59 199.79 0)
			(layer "F.Fab")
			(hide yes)
			(effects
				(font
					(size 1 1)
					(thickness 0.15)
				)
			)
		)
		(property "License" "Apache-2.0"
			(at 5.59 199.79 0)
			(layer "F.Fab")
			(hide yes)
			(effects
				(font
					(size 1 1)
					(thickness 0.15)
				)
			)
		)
		(property "MPN" ""
			(at 5.59 199.79 0)
			(layer "F.Fab")
			(hide yes)
			(effects
				(font
					(size 1 1)
					(thickness 0.15)
				)
			)
		)
		(property "Manufacturer" ""
			(at 5.59 199.79 0)
			(layer "F.Fab")
			(hide yes)
			(effects
				(font
					(size 1 1)
					(thickness 0.15)
				)
			)
		)
		(sheetname "/FPGA/")
		(sheetfile "fpga.kicad_sch")
		(attr exclude_from_pos_files)
		(fp_circle
			(center 0 0)
			(end 0.475 0)
			(stroke
				(width 0.05)
				(type default)
			)
			(fill no)
			(layer "F.CrtYd")
		)
		(fp_text user "License: Apache-2.0"
			(at -0.4 5.101 90)
			(layer "F.Fab")
			(effects
				(font
					(size 0.7 0.7)
					(thickness 0.15)
				)
				(justify right top)
			)
		)
		(fp_text user "${REFERENCE}"
			(at -0.4 2.7 90)
			(layer "F.Fab")
			(effects
				(font
					(size 0.7 0.7)
					(thickness 0.15)
				)
				(justify right top)
			)
		)
		(fp_text user "Author: Antmicro"
			(at -0.4 3.901 90)
			(layer "F.Fab")
			(effects
				(font
					(size 0.7 0.7)
					(thickness 0.15)
				)
				(justify right top)
			)
		)
		(pad "1" smd circle
			(at 0 0 270)
			(size 0.75 0.75)
			(layers "F.Cu" "F.Mask")
			(net 300 "Net-(U18-SI{slash}IO0)")
			(pinfunction "1")
			(pintype "passive")
		)
	)
	(footprint "antmicro-footprints:TP_SMD_0.75mm"
		(layer "F.Cu")
		(at 158.83 74.95)
		(property "Reference" "TP23"
			(at -1.4 -0.51 0)
			(layer "F.SilkS")
			(effects
				(font
					(size 0.65 0.65)
					(thickness 0.15)
				)
				(justify left bottom)
			)
		)
		(property "Value" "TP_0.75mm_SMD"
			(at 0 1.2 0)
			(layer "F.Fab")
			(hide yes)
			(effects
				(font
					(size 0.7 0.7)
					(thickness 0.15)
				)
				(justify left bottom)
			)
		)
		(property "Description" "SMT test point"
			(at 0 0 0)
			(layer "F.Fab")
			(hide yes)
			(effects
				(font
					(size 1.27 1.27)
					(thickness 0.15)
				)
			)
		)
		(property "Author" "Antmicro"
			(at 0 0 0)
			(layer "F.Fab")
			(hide yes)
			(effects
				(font
					(size 1 1)
					(thickness 0.15)
				)
			)
		)
		(property "License" "Apache-2.0"
			(at 0 0 0)
			(layer "F.Fab")
			(hide yes)
			(effects
				(font
					(size 1 1)
					(thickness 0.15)
				)
			)
		)
		(property "MPN" ""
			(at 0 0 0)
			(layer "F.Fab")
			(hide yes)
			(effects
				(font
					(size 1 1)
					(thickness 0.15)
				)
			)
		)
		(property "Manufacturer" ""
			(at 0 0 0)
			(layer "F.Fab")
			(hide yes)
			(effects
				(font
					(size 1 1)
					(thickness 0.15)
				)
			)
		)
		(sheetname "/Power Supply/")
		(sheetfile "supply.kicad_sch")
		(attr exclude_from_pos_files)
		(fp_circle
			(center 0 0)
			(end 0.475 0)
			(stroke
				(width 0.05)
				(type default)
			)
			(fill no)
			(layer "F.CrtYd")
		)
		(fp_text user "License: Apache-2.0"
			(at -0.4 5.101 0)
			(layer "F.Fab")
			(effects
				(font
					(size 0.7 0.7)
					(thickness 0.15)
				)
				(justify left bottom)
			)
		)
		(fp_text user "Author: Antmicro"
			(at -0.4 3.901 0)
			(layer "F.Fab")
			(effects
				(font
					(size 0.7 0.7)
					(thickness 0.15)
				)
				(justify left bottom)
			)
		)
		(fp_text user "${REFERENCE}"
			(at -0.4 2.7 0)
			(layer "F.Fab")
			(effects
				(font
					(size 0.7 0.7)
					(thickness 0.15)
				)
				(justify left bottom)
			)
		)
		(pad "1" smd circle
			(at 0 0)
			(size 0.75 0.75)
			(layers "F.Cu" "F.Mask")
			(net 305 "/Power Supply/~{FAULT}")
			(pinfunction "1")
			(pintype "passive")
		)
	)
)
